(kicad_pcb
	(version 20260206)
	(generator "pcbnew")
	(generator_version "10.0")
	(general
		(thickness 1.6)
		(legacy_teardrops no)
	)
	(paper "A4")
	(title_block
		(title "baseboard — 13948-1b.1110WZS1818.brd")
		(comment 1 "Honey Badger (Wiwynn) / footprints 1064-1070 of 2523")
	)
	(layers
		(0 "F.Cu" signal "TOP")
		(4 "In1.Cu" signal "L2GND")
		(6 "In2.Cu" signal "L3")
		(8 "In3.Cu" signal "L4VCC")
		(10 "In4.Cu" signal "L5VCC")
		(12 "In5.Cu" signal "L6")
		(14 "In6.Cu" signal "L7GND")
		(2 "B.Cu" signal "BOTTOM")
		(9 "F.Adhes" user "F.Adhesive")
		(11 "B.Adhes" user "B.Adhesive")
		(13 "F.Paste" user "Package Geometry/Pastemask Top")
		(15 "B.Paste" user "Package Geometry/Pastemask Bottom")
		(5 "F.SilkS" user "Ref Des/Silkscreen Top")
		(7 "B.SilkS" user "Ref Des/Silkscreen Bottom")
		(1 "F.Mask" user "Board Geometry/Soldermask Top")
		(3 "B.Mask" user "Board Geometry/Soldermask Bottom")
		(17 "Dwgs.User" user "User.Drawings")
		(19 "Cmts.User" user "User.Comments")
		(21 "Eco1.User" user "User.Eco1")
		(23 "Eco2.User" user "User.Eco2")
		(25 "Edge.Cuts" user "Board Geometry/Outline")
		(27 "Margin" user)
		(31 "F.CrtYd" user "Package Geometry/Place Bound Top")
		(29 "B.CrtYd" user "Package Geometry/Place Bound Bottom")
		(35 "F.Fab" user "Ref Des/Assembly Top")
		(33 "B.Fab" user "Ref Des/Assembly Bottom")
	)
	(footprint ""
		(layer "F.Cu")
		(at 85.598 -24.384 180)
		(property "Reference" "PC217"
			(at 0 0 180)
			(layer "F.SilkS")
			(hide yes)
			(effects
				(font
					(size 1.27 1.27)
				)
			)
		)
		(property "Value" "SC220P50V2KX-3GP"
			(at 1.1811 -2.7051 180)
			(unlocked yes)
			(layer "F.Fab")
			(hide yes)
			(effects
				(font
					(size 1.016 1.016)
					(thickness 0.1524)
				)
			)
		)
		(property "Device Type" "C402H22"
			(at 1.1811 -4.2291 180)
			(unlocked yes)
			(layer "F.Fab")
			(hide yes)
			(effects
				(font
					(size 1.016 1.016)
					(thickness 0.1524)
				)
			)
		)
		(duplicate_pad_numbers_are_jumpers no)
		(fp_rect
			(start -0.4318 0.9525)
			(end 0.4318 -0.9525)
			(stroke
				(width 0)
				(type default)
			)
			(fill no)
			(layer "F.CrtYd")
		)
		(fp_rect
			(start -0.4318 0.9525)
			(end 0.4318 -0.9525)
			(stroke
				(width 0)
				(type default)
			)
			(fill no)
			(layer "F.Fab")
		)
		(pad "1" smd custom
			(at 0 -0.4445 180)
			(size 0.1524 0.1524)
			(layers "F.Cu" "F.Mask" "F.Paste")
			(net "VT235_PGIN")
			(options
				(clearance outline)
				(anchor circle)
			)
			(primitives
				(gr_poly
					(pts
						(arc
							(start 0.3048 -0.2032)
							(mid 0.275042 -0.275042)
							(end 0.2032 -0.3048)
						)
						(arc
							(start -0.2032 -0.3048)
							(mid -0.275042 -0.275042)
							(end -0.3048 -0.2032)
						)
						(arc
							(start -0.3048 0.2032)
							(mid -0.275042 0.275042)
							(end -0.2032 0.3048)
						)
						(arc
							(start 0.2032 0.3048)
							(mid 0.275042 0.275042)
							(end 0.3048 0.2032)
						)
					)
					(width 0)
					(fill yes)
				)
			)
		)
		(pad "2" smd custom
			(at 0 0.4445 180)
			(size 0.1524 0.1524)
			(layers "F.Cu" "F.Mask" "F.Paste")
			(net "VT235_VREF")
			(options
				(clearance outline)
				(anchor circle)
			)
			(primitives
				(gr_poly
					(pts
						(arc
							(start 0.3048 -0.2032)
							(mid 0.275042 -0.275042)
							(end 0.2032 -0.3048)
						)
						(arc
							(start -0.2032 -0.3048)
							(mid -0.275042 -0.275042)
							(end -0.3048 -0.2032)
						)
						(arc
							(start -0.3048 0.2032)
							(mid -0.275042 0.275042)
							(end -0.2032 0.3048)
						)
						(arc
							(start 0.2032 0.3048)
							(mid 0.275042 0.275042)
							(end 0.3048 0.2032)
						)
					)
					(width 0)
					(fill yes)
				)
			)
		)
	)
	(footprint ""
		(layer "F.Cu")
		(at 196.977 -179.832 180)
		(property "Reference" "R481"
			(at 0 0 180)
			(layer "F.SilkS")
			(hide yes)
			(effects
				(font
					(size 1.27 1.27)
				)
			)
		)
		(property "Value" "200R3F-GP"
			(at -0.0254 -2.5146 180)
			(unlocked yes)
			(layer "F.Fab")
			(hide yes)
			(effects
				(font
					(size 1.016 1.016)
					(thickness 0.1524)
				)
			)
		)
		(property "Device Type" "R603H22"
			(at -0.0254 -4.0386 180)
			(unlocked yes)
			(layer "F.Fab")
			(hide yes)
			(effects
				(font
					(size 1.016 1.016)
					(thickness 0.1524)
				)
			)
		)
		(duplicate_pad_numbers_are_jumpers no)
		(fp_line
			(start 0.2032 0)
			(end 0.4826 0)
			(stroke
				(width 0.2032)
				(type default)
			)
			(layer "F.SilkS")
		)
		(fp_line
			(start -0.4826 0)
			(end -0.2032 0)
			(stroke
				(width 0.2032)
				(type default)
			)
			(layer "F.SilkS")
		)
		(fp_rect
			(start -0.5842 1.3335)
			(end 0.5842 -1.3335)
			(stroke
				(width 0)
				(type default)
			)
			(fill no)
			(layer "F.CrtYd")
		)
		(fp_rect
			(start -0.5842 1.3335)
			(end 0.5842 -1.3335)
			(stroke
				(width 0)
				(type default)
			)
			(fill no)
			(layer "F.Fab")
		)
		(pad "1" smd custom
			(at 0 -0.762 180)
			(size 0.2159 0.2159)
			(layers "F.Cu" "F.Mask" "F.Paste")
			(net "P3V3_STBY")
			(options
				(clearance outline)
				(anchor circle)
			)
			(primitives
				(gr_poly
					(pts
						(arc
							(start -0.3302 -0.4318)
							(mid -0.402042 -0.402042)
							(end -0.4318 -0.3302)
						)
						(arc
							(start -0.4318 0.3302)
							(mid -0.402042 0.402042)
							(end -0.3302 0.4318)
						)
						(arc
							(start 0.3302 0.4318)
							(mid 0.402042 0.402042)
							(end 0.4318 0.3302)
						)
						(arc
							(start 0.4318 -0.3302)
							(mid 0.402042 -0.402042)
							(end 0.3302 -0.4318)
						)
					)
					(width 0)
					(fill yes)
				)
			)
		)
		(pad "2" smd custom
			(at 0 0.762 180)
			(size 0.2159 0.2159)
			(layers "F.Cu" "F.Mask" "F.Paste")
			(net "HB_A_OUT")
			(options
				(clearance outline)
				(anchor circle)
			)
			(primitives
				(gr_poly
					(pts
						(arc
							(start -0.3302 -0.4318)
							(mid -0.402042 -0.402042)
							(end -0.4318 -0.3302)
						)
						(arc
							(start -0.4318 0.3302)
							(mid -0.402042 0.402042)
							(end -0.3302 0.4318)
						)
						(arc
							(start 0.3302 0.4318)
							(mid 0.402042 0.402042)
							(end 0.4318 0.3302)
						)
						(arc
							(start 0.4318 -0.3302)
							(mid 0.402042 -0.402042)
							(end 0.3302 -0.4318)
						)
					)
					(width 0)
					(fill yes)
				)
			)
		)
	)
	(footprint ""
		(layer "F.Cu")
		(at 274.193 -164.592 90)
		(property "Reference" "R541"
			(at 0 0 90)
			(layer "F.SilkS")
			(hide yes)
			(effects
				(font
					(size 1.27 1.27)
				)
			)
		)
		(property "Value" "0R2J-2-GP"
			(at 0.064008 -3.993896 90)
			(unlocked yes)
			(layer "F.Fab")
			(hide yes)
			(effects
				(font
					(size 1.016 1.016)
					(thickness 0.1524)
				)
			)
		)
		(property "Device Type" "R402H16"
			(at 0.064008 -5.517896 90)
			(unlocked yes)
			(layer "F.Fab")
			(hide yes)
			(effects
				(font
					(size 1.016 1.016)
					(thickness 0.1524)
				)
			)
		)
		(duplicate_pad_numbers_are_jumpers no)
		(fp_line
			(start 0.508 -0.9398)
			(end -0.508 -0.9398)
			(stroke
				(width 0.1524)
				(type default)
			)
			(layer "F.SilkS")
		)
		(fp_line
			(start -0.508 -0.9398)
			(end -0.508 0.9398)
			(stroke
				(width 0.1524)
				(type default)
			)
			(layer "F.SilkS")
		)
		(fp_rect
			(start -0.508 0.9398)
			(end 0.508 -0.9398)
			(stroke
				(width 0)
				(type default)
			)
			(fill no)
			(layer "F.CrtYd")
		)
		(fp_rect
			(start -0.508 0.9398)
			(end 0.508 -0.9398)
			(stroke
				(width 0)
				(type default)
			)
			(fill no)
			(layer "F.Fab")
		)
		(pad "1" smd custom
			(at 0 -0.4445 90)
			(size 0.1397 0.1397)
			(layers "F.Cu" "F.Mask" "F.Paste")
			(net "P0V9_E_PG")
			(options
				(clearance outline)
				(anchor circle)
			)
			(primitives
				(gr_poly
					(pts
						(arc
							(start -0.1778 -0.2794)
							(mid -0.249642 -0.249642)
							(end -0.2794 -0.1778)
						)
						(arc
							(start -0.2794 0.1778)
							(mid -0.249642 0.249642)
							(end -0.1778 0.2794)
						)
						(arc
							(start 0.1778 0.2794)
							(mid 0.249642 0.249642)
							(end 0.2794 0.1778)
						)
						(arc
							(start 0.2794 -0.1778)
							(mid 0.249642 -0.249642)
							(end 0.1778 -0.2794)
						)
					)
					(width 0)
					(fill yes)
				)
			)
		)
		(pad "2" smd custom
			(at 0 0.4445 90)
			(size 0.1397 0.1397)
			(layers "F.Cu" "F.Mask" "F.Paste")
			(net "PWGD_P0V9_E_PG_R")
			(options
				(clearance outline)
				(anchor circle)
			)
			(primitives
				(gr_poly
					(pts
						(arc
							(start -0.1778 -0.2794)
							(mid -0.249642 -0.249642)
							(end -0.2794 -0.1778)
						)
						(arc
							(start -0.2794 0.1778)
							(mid -0.249642 0.249642)
							(end -0.1778 0.2794)
						)
						(arc
							(start 0.1778 0.2794)
							(mid 0.249642 0.249642)
							(end 0.2794 0.1778)
						)
						(arc
							(start 0.2794 -0.1778)
							(mid 0.249642 -0.249642)
							(end 0.1778 -0.2794)
						)
					)
					(width 0)
					(fill yes)
				)
			)
		)
	)
	(footprint ""
		(layer "F.Cu")
		(at 182.888128 -16.183864)
		(property "Reference" "R189"
			(at 0 0 0)
			(layer "F.SilkS")
			(hide yes)
			(effects
				(font
					(size 1.27 1.27)
				)
			)
		)
		(property "Value" "4K7R2F-GP"
			(at 0.064008 -3.993896 0)
			(unlocked yes)
			(layer "F.Fab")
			(hide yes)
			(effects
				(font
					(size 1.016 1.016)
					(thickness 0.1524)
				)
			)
		)
		(property "Device Type" "R402H16"
			(at 0.064008 -5.517896 0)
			(unlocked yes)
			(layer "F.Fab")
			(hide yes)
			(effects
				(font
					(size 1.016 1.016)
					(thickness 0.1524)
				)
			)
		)
		(duplicate_pad_numbers_are_jumpers no)
		(fp_line
			(start -0.508 -0.9398)
			(end -0.508 0.9398)
			(stroke
				(width 0.1524)
				(type default)
			)
			(layer "F.SilkS")
		)
		(fp_line
			(start 0.508 -0.9398)
			(end -0.508 -0.9398)
			(stroke
				(width 0.1524)
				(type default)
			)
			(layer "F.SilkS")
		)
		(fp_rect
			(start -0.508 0.9398)
			(end 0.508 -0.9398)
			(stroke
				(width 0)
				(type default)
			)
			(fill no)
			(layer "F.CrtYd")
		)
		(fp_rect
			(start -0.508 0.9398)
			(end 0.508 -0.9398)
			(stroke
				(width 0)
				(type default)
			)
			(fill no)
			(layer "F.Fab")
		)
		(pad "1" smd custom
			(at 0 -0.4445)
			(size 0.1397 0.1397)
			(layers "F.Cu" "F.Mask" "F.Paste")
			(net "P3V3_STBY")
			(options
				(clearance outline)
				(anchor circle)
			)
			(primitives
				(gr_poly
					(pts
						(arc
							(start -0.1778 -0.2794)
							(mid -0.249642 -0.249642)
							(end -0.2794 -0.1778)
						)
						(arc
							(start -0.2794 0.1778)
							(mid -0.249642 0.249642)
							(end -0.1778 0.2794)
						)
						(arc
							(start 0.1778 0.2794)
							(mid 0.249642 0.249642)
							(end 0.2794 0.1778)
						)
						(arc
							(start 0.2794 -0.1778)
							(mid 0.249642 -0.249642)
							(end 0.1778 -0.2794)
						)
					)
					(width 0)
					(fill yes)
				)
			)
		)
		(pad "2" smd custom
			(at 0 0.4445)
			(size 0.1397 0.1397)
			(layers "F.Cu" "F.Mask" "F.Paste")
			(net "TEMP_1_A1")
			(options
				(clearance outline)
				(anchor circle)
			)
			(primitives
				(gr_poly
					(pts
						(arc
							(start -0.1778 -0.2794)
							(mid -0.249642 -0.249642)
							(end -0.2794 -0.1778)
						)
						(arc
							(start -0.2794 0.1778)
							(mid -0.249642 0.249642)
							(end -0.1778 0.2794)
						)
						(arc
							(start 0.1778 0.2794)
							(mid 0.249642 0.249642)
							(end 0.2794 0.1778)
						)
						(arc
							(start 0.2794 -0.1778)
							(mid 0.249642 -0.249642)
							(end 0.1778 -0.2794)
						)
					)
					(width 0)
					(fill yes)
				)
			)
		)
	)
	(footprint ""
		(layer "F.Cu")
		(at 9.348216 -215.19388 90)
		(property "Reference" "U50"
			(at 0 0 90)
			(layer "F.SilkS")
			(hide yes)
			(effects
				(font
					(size 1.27 1.27)
				)
			)
		)
		(property "Value" "SN74LVC1G08DCKR-GP"
			(at -2.3368 -8.6868 90)
			(unlocked yes)
			(layer "F.Fab")
			(hide yes)
			(effects
				(font
					(size 1.016 1.016)
					(thickness 0.1524)
				)
			)
		)
		(property "Device Type" "SC70-5H44"
			(at -2.3114 -10.414 90)
			(unlocked yes)
			(layer "F.Fab")
			(hide yes)
			(effects
				(font
					(size 1.016 1.016)
					(thickness 0.1524)
				)
			)
		)
		(duplicate_pad_numbers_are_jumpers no)
		(fp_line
			(start 1.3843 -1.8034)
			(end 1.3843 -1.1176)
			(stroke
				(width 0.3302)
				(type default)
			)
			(layer "F.SilkS")
		)
		(fp_line
			(start 0.6604 -1.8034)
			(end 1.3843 -1.8034)
			(stroke
				(width 0.3302)
				(type default)
			)
			(layer "F.SilkS")
		)
		(fp_line
			(start 1.27 -1.7018)
			(end 1.27 1.7018)
			(stroke
				(width 0.1524)
				(type default)
			)
			(layer "F.SilkS")
		)
		(fp_line
			(start -1.27 -1.7018)
			(end 1.27 -1.7018)
			(stroke
				(width 0.1524)
				(type default)
			)
			(layer "F.SilkS")
		)
		(fp_line
			(start 1.27 1.7018)
			(end -1.27 1.7018)
			(stroke
				(width 0.1524)
				(type default)
			)
			(layer "F.SilkS")
		)
		(fp_line
			(start -1.27 1.7018)
			(end -1.27 -1.7018)
			(stroke
				(width 0.1524)
				(type default)
			)
			(layer "F.SilkS")
		)
		(fp_rect
			(start -1.524 1.9558)
			(end 1.524 -1.9558)
			(stroke
				(width 0)
				(type default)
			)
			(fill no)
			(layer "F.CrtYd")
		)
		(fp_poly
			(pts
				(xy -1.524 -1.9558) (xy 1.524 -1.9558) (xy 1.524 1.9558) (xy -1.524 1.9558)
			)
			(stroke
				(width 0)
				(type default)
			)
			(fill no)
			(layer "F.Fab")
		)
		(pad "1" smd rect
			(at 0.65024 -0.8255 90)
			(size 0.4064 1.2192)
			(layers "F.Cu" "F.Mask" "F.Paste")
			(net "PRSNT_AND_1")
		)
		(pad "2" smd rect
			(at 0 -0.8255 90)
			(size 0.4064 1.2192)
			(layers "F.Cu" "F.Mask" "F.Paste")
			(net "PRSNT_AND_3")
		)
		(pad "3" smd rect
			(at -0.65024 -0.8255 90)
			(size 0.4064 1.2192)
			(layers "F.Cu" "F.Mask" "F.Paste")
			(net "GND")
		)
		(pad "4" smd rect
			(at -0.65024 0.8255 90)
			(size 0.4064 1.2192)
			(layers "F.Cu" "F.Mask" "F.Paste")
			(net "MATED#")
		)
		(pad "5" smd rect
			(at 0.65024 0.8255 90)
			(size 0.4064 1.2192)
			(layers "F.Cu" "F.Mask" "F.Paste")
			(net "P3V3_STBY")
		)
	)
	(footprint ""
		(layer "F.Cu")
		(at 190.871856 -120.913652 90)
		(property "Reference" "R600"
			(at 0 0 90)
			(layer "F.SilkS")
			(hide yes)
			(effects
				(font
					(size 1.27 1.27)
				)
			)
		)
		(property "Value" "1KR2J-1-GP"
			(at 0.064008 -3.993896 90)
			(unlocked yes)
			(layer "F.Fab")
			(hide yes)
			(effects
				(font
					(size 1.016 1.016)
					(thickness 0.1524)
				)
			)
		)
		(property "Device Type" "R402H16"
			(at 0.064008 -5.517896 90)
			(unlocked yes)
			(layer "F.Fab")
			(hide yes)
			(effects
				(font
					(size 1.016 1.016)
					(thickness 0.1524)
				)
			)
		)
		(duplicate_pad_numbers_are_jumpers no)
		(fp_line
			(start 0.508 -0.9398)
			(end -0.508 -0.9398)
			(stroke
				(width 0.1524)
				(type default)
			)
			(layer "F.SilkS")
		)
		(fp_line
			(start -0.508 -0.9398)
			(end -0.508 0.9398)
			(stroke
				(width 0.1524)
				(type default)
			)
			(layer "F.SilkS")
		)
		(fp_rect
			(start -0.508 0.9398)
			(end 0.508 -0.9398)
			(stroke
				(width 0)
				(type default)
			)
			(fill no)
			(layer "F.CrtYd")
		)
		(fp_rect
			(start -0.508 0.9398)
			(end 0.508 -0.9398)
			(stroke
				(width 0)
				(type default)
			)
			(fill no)
			(layer "F.Fab")
		)
		(pad "1" smd custom
			(at 0 -0.4445 90)
			(size 0.1397 0.1397)
			(layers "F.Cu" "F.Mask" "F.Paste")
			(net "P3V3_STBY_R2")
			(options
				(clearance outline)
				(anchor circle)
			)
			(primitives
				(gr_poly
					(pts
						(arc
							(start -0.1778 -0.2794)
							(mid -0.249642 -0.249642)
							(end -0.2794 -0.1778)
						)
						(arc
							(start -0.2794 0.1778)
							(mid -0.249642 0.249642)
							(end -0.1778 0.2794)
						)
						(arc
							(start 0.1778 0.2794)
							(mid 0.249642 0.249642)
							(end 0.2794 0.1778)
						)
						(arc
							(start 0.2794 -0.1778)
							(mid 0.249642 -0.249642)
							(end 0.1778 -0.2794)
						)
					)
					(width 0)
					(fill yes)
				)
			)
		)
		(pad "2" smd custom
			(at 0 0.4445 90)
			(size 0.1397 0.1397)
			(layers "F.Cu" "F.Mask" "F.Paste")
			(net "P5V_STBY")
			(options
				(clearance outline)
				(anchor circle)
			)
			(primitives
				(gr_poly
					(pts
						(arc
							(start -0.1778 -0.2794)
							(mid -0.249642 -0.249642)
							(end -0.2794 -0.1778)
						)
						(arc
							(start -0.2794 0.1778)
							(mid -0.249642 0.249642)
							(end -0.1778 0.2794)
						)
						(arc
							(start 0.1778 0.2794)
							(mid 0.249642 0.249642)
							(end 0.2794 0.1778)
						)
						(arc
							(start 0.2794 -0.1778)
							(mid 0.249642 -0.249642)
							(end 0.1778 -0.2794)
						)
					)
					(width 0)
					(fill yes)
				)
			)
		)
	)
	(footprint ""
		(layer "F.Cu")
		(at 110.109 -60.452 180)
		(property "Reference" "SR695"
			(at 0 0 180)
			(layer "F.SilkS")
			(hide yes)
			(effects
				(font
					(size 1.27 1.27)
				)
			)
		)
		(property "Value" "10KR2F-2-GP"
			(at 0.064008 -3.993896 180)
			(unlocked yes)
			(layer "F.Fab")
			(hide yes)
			(effects
				(font
					(size 1.016 1.016)
					(thickness 0.1524)
				)
			)
		)
		(property "Device Type" "R402H16"
			(at 0.064008 -5.517896 180)
			(unlocked yes)
			(layer "F.Fab")
			(hide yes)
			(effects
				(font
					(size 1.016 1.016)
					(thickness 0.1524)
				)
			)
		)
		(duplicate_pad_numbers_are_jumpers no)
		(fp_line
			(start 0.508 -0.9398)
			(end -0.508 -0.9398)
			(stroke
				(width 0.1524)
				(type default)
			)
			(layer "F.SilkS")
		)
		(fp_line
			(start -0.508 -0.9398)
			(end -0.508 0.9398)
			(stroke
				(width 0.1524)
				(type default)
			)
			(layer "F.SilkS")
		)
		(fp_rect
			(start -0.508 0.9398)
			(end 0.508 -0.9398)
			(stroke
				(width 0)
				(type default)
			)
			(fill no)
			(layer "F.CrtYd")
		)
		(fp_rect
			(start -0.508 0.9398)
			(end 0.508 -0.9398)
			(stroke
				(width 0)
				(type default)
			)
			(fill no)
			(layer "F.Fab")
		)
		(pad "1" smd custom
			(at 0 -0.4445 180)
			(size 0.1397 0.1397)
			(layers "F.Cu" "F.Mask" "F.Paste")
			(net "XM_ADDR_0")
			(options
				(clearance outline)
				(anchor circle)
			)
			(primitives
				(gr_poly
					(pts
						(arc
							(start -0.1778 -0.2794)
							(mid -0.249642 -0.249642)
							(end -0.2794 -0.1778)
						)
						(arc
							(start -0.2794 0.1778)
							(mid -0.249642 0.249642)
							(end -0.1778 0.2794)
						)
						(arc
							(start 0.1778 0.2794)
							(mid 0.249642 0.249642)
							(end 0.2794 0.1778)
						)
						(arc
							(start 0.2794 -0.1778)
							(mid 0.249642 -0.249642)
							(end 0.1778 -0.2794)
						)
					)
					(width 0)
					(fill yes)
				)
			)
		)
		(pad "2" smd custom
			(at 0 0.4445 180)
			(size 0.1397 0.1397)
			(layers "F.Cu" "F.Mask" "F.Paste")
			(net "GND")
			(options
				(clearance outline)
				(anchor circle)
			)
			(primitives
				(gr_poly
					(pts
						(arc
							(start -0.1778 -0.2794)
							(mid -0.249642 -0.249642)
							(end -0.2794 -0.1778)
						)
						(arc
							(start -0.2794 0.1778)
							(mid -0.249642 0.249642)
							(end -0.1778 0.2794)
						)
						(arc
							(start 0.1778 0.2794)
							(mid 0.249642 0.249642)
							(end 0.2794 0.1778)
						)
						(arc
							(start 0.2794 -0.1778)
							(mid 0.249642 -0.249642)
							(end 0.1778 -0.2794)
						)
					)
					(width 0)
					(fill yes)
				)
			)
		)
	)
)
